FILE_TYPE = MULTI_PHYS_TABLE;
PART 'SWITCH_D37771002'
{====================================================================================================================================================================}
:PACK_TYPE|MATERIAL  |PART_NUMBER      = EnvComp |PART_NUMBER   |JEDEC_TYPE  |CLASS  |DESCRIPTION                                 |HEIGHT      |COMPONENT_TYPE| LPID | SPEED_URL | Status |RPL| AML | Bus_Unit | Days ;
{====================================================================================================================================================================}
'SM'      | 'IC'     | 'D37771-002'(!) = 'UNK;UNK;UNK;UNK;ok;CIP' | 'D37771-002' | 'SSW4RPE'  | 'IC'  | 'CONN,SWIT,TACTILE,VT,SPST,1,50.0V,SMT'    | '0.396 IN' | 'SMTOTHER'   | '' | 'http://speed.intel.com:8081/speed/module/pdm/item/pdm_item_detail_direct.asp?item_cde=D37771-002&item_rev=01&url_param=unused' | 'Design' | 'NO' | '1' | 'SMO_BOARDS' | '???' 
'SM'      | 'EMPTY'  | 'D37771-002'(!) = 'UNK;UNK;UNK;UNK;ok;CIP' | 'D37771-002' | 'SSW4RPE'  | 'IO'  | 'CONN,SWIT,TACTILE,VT,SPST,1,50.0V,SMT'    | '0.396 IN' | 'SMTOTHER'   | '' | 'http://speed.intel.com:8081/speed/module/pdm/item/pdm_item_detail_direct.asp?item_cde=D37771-002&item_rev=01&url_param=unused' | 'Design' | 'NO' | '1' | 'SMO_BOARDS' | '???' 
END_PART
END.
